(kicad_pcb
	(version 20260206)
	(generator "pcbnew")
	(generator_version "10.0")
	(general
		(thickness 1.6)
		(legacy_teardrops no)
	)
	(paper "A4")
	(title_block
		(title "v1-chassis-manager — T6M_CM_d_v01_1031_1645.brd")
		(comment 1 "Open CloudServer (Microsoft) / footprint 1507 of 2512 (U2), pads 120-239 of 1283")
	)
	(layers
		(0 "F.Cu" signal "TOP")
		(4 "In1.Cu" signal "GND1")
		(6 "In2.Cu" signal "IN1")
		(8 "In3.Cu" signal "VCC1")
		(10 "In4.Cu" signal "VCC2")
		(12 "In5.Cu" signal "GND2")
		(14 "In6.Cu" signal "IN2")
		(16 "In7.Cu" signal "IN3")
		(18 "In8.Cu" signal "GND3")
		(2 "B.Cu" signal "BOTTOM")
		(9 "F.Adhes" user "F.Adhesive")
		(11 "B.Adhes" user "B.Adhesive")
		(13 "F.Paste" user "Package Geometry/Pastemask Top")
		(15 "B.Paste" user "Package Geometry/Pastemask Bottom")
		(5 "F.SilkS" user "Ref Des/Silkscreen Top")
		(7 "B.SilkS" user "Ref Des/Silkscreen Bottom")
		(1 "F.Mask" user "Board Geometry/Soldermask Top")
		(3 "B.Mask" user "Board Geometry/Soldermask Bottom")
		(17 "Dwgs.User" user "User.Drawings")
		(19 "Cmts.User" user "User.Comments")
		(21 "Eco1.User" user "User.Eco1")
		(23 "Eco2.User" user "User.Eco2")
		(25 "Edge.Cuts" user "Board Geometry/Outline")
		(27 "Margin" user)
		(31 "F.CrtYd" user "Package Geometry/Place Bound Top")
		(29 "B.CrtYd" user "Package Geometry/Place Bound Bottom")
		(35 "F.Fab" user "Ref Des/Assembly Top")
		(33 "B.Fab" user "Ref Des/Assembly Bottom")
	)
	(footprint ""
		(layer "F.Cu")
		(at 58.000646 -75.799442)
		(property "Reference" "U2"
			(at -20.2438 -18.364708 0)
			(unlocked yes)
			(layer "F.SilkS")
			(effects
				(font
					(size 1.6002 1.1938)
					(thickness 0.1524)
				)
				(justify left)
			)
		)
		(property "Value" ""
			(at 0 0 0)
			(layer "F.Fab")
			(effects
				(font
					(size 1.27 1.27)
				)
			)
		)
		(duplicate_pad_numbers_are_jumpers no)
		(pad "AD50" smd circle
			(at 8.391398 -1.756156)
			(size 0.3048 0.3048)
			(layers "F.Cu" "F.Mask" "F.Paste")
			(net "GND")
		)
		(pad "AD52" smd circle
			(at 9.153398 -1.756156)
			(size 0.3048 0.3048)
			(layers "F.Cu" "F.Mask" "F.Paste")
			(net "PD_CPU_NODE1_HVMGEAR_SEL")
		)
		(pad "AD53" smd circle
			(at 9.915398 -1.756156)
			(size 0.3048 0.3048)
			(layers "F.Cu" "F.Mask" "F.Paste")
			(net "PD_CPU_NODE1_MEM_SPEED1")
		)
		(pad "AD55" smd circle
			(at 10.677398 -1.756156)
			(size 0.3048 0.3048)
			(layers "F.Cu" "F.Mask" "F.Paste")
			(net "GND")
		)
		(pad "AD56" smd circle
			(at 11.439398 -1.756156)
			(size 0.3048 0.3048)
			(layers "F.Cu" "F.Mask" "F.Paste")
			(net "PU_CPU_NODE1_MEM_SPEED0")
		)
		(pad "AD58" smd circle
			(at 12.201398 -1.756156)
			(size 0.3048 0.3048)
			(layers "F.Cu" "F.Mask" "F.Paste")
			(net "PWRGD_CPU_NODE1_EPWRGOOD")
		)
		(pad "AD59" smd circle
			(at 12.963398 -1.756156)
			(size 0.3048 0.3048)
			(layers "F.Cu" "F.Mask" "F.Paste")
			(net "GND")
		)
		(pad "AD62" smd circle
			(at 14.204442 -1.994916)
			(size 0.3048 0.3048)
			(layers "F.Cu" "F.Mask" "F.Paste")
			(net "XDP_SOC_CPU_NODE1_TCK")
		)
		(pad "AD63" smd circle
			(at 14.90091 -1.897888)
			(size 0.3048 0.3048)
			(layers "F.Cu" "F.Mask" "F.Paste")
			(net "XDP_SOC_CPU_NODE1_TMS")
		)
		(pad "AD65" smd circle
			(at 15.640812 -1.891792)
			(size 0.3048 0.3048)
			(layers "F.Cu" "F.Mask" "F.Paste")
			(net "GND")
		)
		(pad "AD66" smd oval
			(at 16.249396 -1.542288 90)
			(size 0.254 0.3429)
			(layers "F.Cu" "F.Mask" "F.Paste")
			(net "GND")
		)
		(pad "AE1" smd oval
			(at -16.249396 -1.335024 270)
			(size 0.254 0.3429)
			(layers "F.Cu" "F.Mask" "F.Paste")
			(net "GND")
		)
		(pad "AE3" smd circle
			(at -15.242794 -1.104646)
			(size 0.3048 0.3048)
			(layers "F.Cu" "F.Mask" "F.Paste")
			(net "GND")
		)
		(pad "AE5" smd circle
			(at -14.08049 -1.114552)
			(size 0.3048 0.3048)
			(layers "F.Cu" "F.Mask" "F.Paste")
			(net "GND")
		)
		(pad "AE47" smd circle
			(at 6.841998 -1.056132)
			(size 0.3048 0.3048)
			(layers "F.Cu" "F.Mask" "F.Paste")
			(net "GND")
		)
		(pad "AE62" smd circle
			(at 14.013688 -1.316736)
			(size 0.3048 0.3048)
			(layers "F.Cu" "F.Mask" "F.Paste")
			(net "XDP_CPU_NODE1_PREQ_L")
		)
		(pad "AE64" smd circle
			(at 15.247112 -1.28651)
			(size 0.3048 0.3048)
			(layers "F.Cu" "F.Mask" "F.Paste")
			(net "A_CPU_NODE1_AE64_PU")
		)
		(pad "AF2" smd circle
			(at -15.752318 -0.617728)
			(size 0.3048 0.3048)
			(layers "F.Cu" "F.Mask" "F.Paste")
			(net "PD_CPU_NODE1_RP1_PERN")
		)
		(pad "AF4" smd circle
			(at -14.794738 -0.564896)
			(size 0.3048 0.3048)
			(layers "F.Cu" "F.Mask" "F.Paste")
			(net "PD_CPU_NODE1_RP1_PERP")
		)
		(pad "AF20" smd circle
			(at -6.841998 -0.816356)
			(size 0.3048 0.3048)
			(layers "F.Cu" "F.Mask" "F.Paste")
			(net "GND")
		)
		(pad "AF21" smd circle
			(at -6.00075 -0.8001)
			(size 0.381 0.381)
			(layers "F.Cu" "F.Mask" "F.Paste")
			(net "GND")
		)
		(pad "AF23" smd circle
			(at -5.20065 -0.8001)
			(size 0.381 0.381)
			(layers "F.Cu" "F.Mask" "F.Paste")
			(net "P3V3_NODE1")
		)
		(pad "AF25" smd circle
			(at -4.40055 -0.8001)
			(size 0.381 0.381)
			(layers "F.Cu" "F.Mask" "F.Paste")
			(net "GND")
		)
		(pad "AF26" smd circle
			(at -3.60045 -0.8001)
			(size 0.381 0.381)
			(layers "F.Cu" "F.Mask" "F.Paste")
			(net "GND")
		)
		(pad "AF28" smd circle
			(at -2.80035 -0.8001)
			(size 0.381 0.381)
			(layers "F.Cu" "F.Mask" "F.Paste")
			(net "P1V5_NODE1")
		)
		(pad "AF29" smd circle
			(at -2.00025 -0.8001)
			(size 0.381 0.381)
			(layers "F.Cu" "F.Mask" "F.Paste")
			(net "GND")
		)
		(pad "AF31" smd circle
			(at -1.20015 -0.8001)
			(size 0.381 0.381)
			(layers "F.Cu" "F.Mask" "F.Paste")
			(net "P1V05_NODE1")
		)
		(pad "AF32" smd circle
			(at -0.40005 -0.8001)
			(size 0.381 0.381)
			(layers "F.Cu" "F.Mask" "F.Paste")
			(net "GND")
		)
		(pad "AF34" smd circle
			(at 0.40005 -0.8001)
			(size 0.381 0.381)
			(layers "F.Cu" "F.Mask" "F.Paste")
			(net "GND")
		)
		(pad "AF36" smd circle
			(at 1.20015 -0.8001)
			(size 0.381 0.381)
			(layers "F.Cu" "F.Mask" "F.Paste")
			(net "P1V05_NODE1")
		)
		(pad "AF38" smd circle
			(at 2.00025 -0.8001)
			(size 0.381 0.381)
			(layers "F.Cu" "F.Mask" "F.Paste")
			(net "A_CPU1_NODE1_THERMDC")
		)
		(pad "AF39" smd circle
			(at 2.80035 -0.8001)
			(size 0.381 0.381)
			(layers "F.Cu" "F.Mask" "F.Paste")
			(net "GND")
		)
		(pad "AF41" smd circle
			(at 3.60045 -0.8001)
			(size 0.381 0.381)
			(layers "F.Cu" "F.Mask" "F.Paste")
			(net "VSENSE_VSS_CPU_NODE1")
		)
		(pad "AF42" smd circle
			(at 4.40055 -0.8001)
			(size 0.381 0.381)
			(layers "F.Cu" "F.Mask" "F.Paste")
			(net "GND")
		)
		(pad "AF44" smd circle
			(at 5.20065 -0.8001)
			(size 0.381 0.381)
			(layers "F.Cu" "F.Mask" "F.Paste")
			(net "GND")
		)
		(pad "AF46" smd circle
			(at 6.00075 -0.8001)
			(size 0.381 0.381)
			(layers "F.Cu" "F.Mask" "F.Paste")
			(net "GND")
		)
		(pad "AF62" smd circle
			(at 14.063218 -0.614426)
			(size 0.3048 0.3048)
			(layers "F.Cu" "F.Mask" "F.Paste")
			(net "GND")
		)
		(pad "AF63" smd circle
			(at 14.751558 -0.783336)
			(size 0.3048 0.3048)
			(layers "F.Cu" "F.Mask" "F.Paste")
			(net "Net_444")
		)
		(pad "AF65" smd circle
			(at 15.805658 -0.863092)
			(size 0.3048 0.3048)
			(layers "F.Cu" "F.Mask" "F.Paste")
			(net "GND")
		)
		(pad "AG5" smd circle
			(at -14.063218 -0.407162)
			(size 0.3048 0.3048)
			(layers "F.Cu" "F.Mask" "F.Paste")
			(net "PD_CPU_NODE1_RP1_PERP")
		)
		(pad "AG7" smd circle
			(at -13.344398 -0.230124)
			(size 0.3048 0.3048)
			(layers "F.Cu" "F.Mask" "F.Paste")
			(net "GND")
		)
		(pad "AG8" smd circle
			(at -12.582398 -0.230124)
			(size 0.3048 0.3048)
			(layers "F.Cu" "F.Mask" "F.Paste")
			(net "Net_386")
		)
		(pad "AG10" smd circle
			(at -11.820398 -0.230124)
			(size 0.3048 0.3048)
			(layers "F.Cu" "F.Mask" "F.Paste")
			(net "Net_379")
		)
		(pad "AG11" smd circle
			(at -11.058398 -0.230124)
			(size 0.3048 0.3048)
			(layers "F.Cu" "F.Mask" "F.Paste")
			(net "GND")
		)
		(pad "AG13" smd circle
			(at -10.296398 -0.230124)
			(size 0.3048 0.3048)
			(layers "F.Cu" "F.Mask" "F.Paste")
			(net "Net_374")
		)
		(pad "AG14" smd circle
			(at -9.534398 -0.230124)
			(size 0.3048 0.3048)
			(layers "F.Cu" "F.Mask" "F.Paste")
			(net "Net_373")
		)
		(pad "AG16" smd circle
			(at -8.772398 -0.230124)
			(size 0.3048 0.3048)
			(layers "F.Cu" "F.Mask" "F.Paste")
			(net "GND")
		)
		(pad "AG17" smd circle
			(at -8.010398 -0.230124)
			(size 0.3048 0.3048)
			(layers "F.Cu" "F.Mask" "F.Paste")
			(net "GND")
		)
		(pad "AG19" smd circle
			(at -7.248398 -0.230124)
			(size 0.3048 0.3048)
			(layers "F.Cu" "F.Mask" "F.Paste")
			(net "GND")
		)
		(pad "AG21" smd circle
			(at -6.00075 0)
			(size 0.381 0.381)
			(layers "F.Cu" "F.Mask" "F.Paste")
			(net "GND")
		)
		(pad "AG23" smd circle
			(at -5.20065 0)
			(size 0.381 0.381)
			(layers "F.Cu" "F.Mask" "F.Paste")
			(net "TP_P1V8_VCCABGTS_NODE1")
		)
		(pad "AG25" smd circle
			(at -4.40055 0)
			(size 0.381 0.381)
			(layers "F.Cu" "F.Mask" "F.Paste")
			(net "GND")
		)
		(pad "AG26" smd circle
			(at -3.60045 0)
			(size 0.381 0.381)
			(layers "F.Cu" "F.Mask" "F.Paste")
			(net "GND")
		)
		(pad "AG28" smd circle
			(at -2.80035 0)
			(size 0.381 0.381)
			(layers "F.Cu" "F.Mask" "F.Paste")
			(net "P1V8_NODE1")
		)
		(pad "AG29" smd circle
			(at -2.00025 0)
			(size 0.381 0.381)
			(layers "F.Cu" "F.Mask" "F.Paste")
			(net "P1V05_NODE1")
		)
		(pad "AG31" smd circle
			(at -1.20015 0)
			(size 0.381 0.381)
			(layers "F.Cu" "F.Mask" "F.Paste")
			(net "GND")
		)
		(pad "AG32" smd circle
			(at -0.40005 0)
			(size 0.381 0.381)
			(layers "F.Cu" "F.Mask" "F.Paste")
			(net "P1V05_NODE1")
		)
		(pad "AG34" smd circle
			(at 0.40005 0)
			(size 0.381 0.381)
			(layers "F.Cu" "F.Mask" "F.Paste")
			(net "P1V05_NODE1")
		)
		(pad "AG36" smd circle
			(at 1.20015 0)
			(size 0.381 0.381)
			(layers "F.Cu" "F.Mask" "F.Paste")
			(net "P1V05_NODE1")
		)
		(pad "AG38" smd circle
			(at 2.00025 0)
			(size 0.381 0.381)
			(layers "F.Cu" "F.Mask" "F.Paste")
			(net "GND")
		)
		(pad "AG39" smd circle
			(at 2.80035 0)
			(size 0.381 0.381)
			(layers "F.Cu" "F.Mask" "F.Paste")
			(net "A_CPU1_NODE1_THERMDA")
		)
		(pad "AG41" smd circle
			(at 3.60045 0)
			(size 0.381 0.381)
			(layers "F.Cu" "F.Mask" "F.Paste")
			(net "TP_CPU_NODE1_VCCCPU1VIDSI0GT1P0")
		)
		(pad "AG42" smd circle
			(at 4.40055 0)
			(size 0.381 0.381)
			(layers "F.Cu" "F.Mask" "F.Paste")
			(net "TP_CPU_NODE1_VCCCPU1VIDSI0GT1_1")
		)
		(pad "AG44" smd circle
			(at 5.20065 0)
			(size 0.381 0.381)
			(layers "F.Cu" "F.Mask" "F.Paste")
			(net "GND")
		)
		(pad "AG46" smd circle
			(at 6.00075 0)
			(size 0.381 0.381)
			(layers "F.Cu" "F.Mask" "F.Paste")
			(net "GND")
		)
		(pad "AG48" smd circle
			(at 7.248398 -0.4699)
			(size 0.3048 0.3048)
			(layers "F.Cu" "F.Mask" "F.Paste")
			(net "PD_CPU_NODE1_PUNIT_ST_ADDR0")
		)
		(pad "AG50" smd circle
			(at 8.010398 -0.4699)
			(size 0.3048 0.3048)
			(layers "F.Cu" "F.Mask" "F.Paste")
			(net "TP_CPU1_NODE1_HFPLL")
		)
		(pad "AG51" smd circle
			(at 8.772398 -0.4699)
			(size 0.3048 0.3048)
			(layers "F.Cu" "F.Mask" "F.Paste")
			(net "GND")
		)
		(pad "AG53" smd circle
			(at 9.534398 -0.4699)
			(size 0.3048 0.3048)
			(layers "F.Cu" "F.Mask" "F.Paste")
			(net "Net_449")
		)
		(pad "AG54" smd circle
			(at 10.296398 -0.4699)
			(size 0.3048 0.3048)
			(layers "F.Cu" "F.Mask" "F.Paste")
			(net "TP_CPU_NODE1_IERR_LV")
		)
		(pad "AG56" smd circle
			(at 11.058398 -0.4699)
			(size 0.3048 0.3048)
			(layers "F.Cu" "F.Mask" "F.Paste")
			(net "GND")
		)
		(pad "AG57" smd circle
			(at 11.820398 -0.4699)
			(size 0.3048 0.3048)
			(layers "F.Cu" "F.Mask" "F.Paste")
			(net "Net_299")
		)
		(pad "AG59" smd circle
			(at 12.582398 -0.4699)
			(size 0.3048 0.3048)
			(layers "F.Cu" "F.Mask" "F.Paste")
			(net "H_CPU_NODE1_THRMTRIP_L")
		)
		(pad "AG60" smd circle
			(at 13.344398 -0.4699)
			(size 0.3048 0.3048)
			(layers "F.Cu" "F.Mask" "F.Paste")
			(net "Net_446")
		)
		(pad "AG63" smd circle
			(at 14.542516 -0.103632)
			(size 0.3048 0.3048)
			(layers "F.Cu" "F.Mask" "F.Paste")
			(net "Net_439")
		)
		(pad "AG64" smd circle
			(at 15.304516 -0.052832)
			(size 0.3048 0.3048)
			(layers "F.Cu" "F.Mask" "F.Paste")
			(net "Net_445")
		)
		(pad "AG66" smd oval
			(at 16.249396 -0.103632 90)
			(size 0.254 0.3429)
			(layers "F.Cu" "F.Mask" "F.Paste")
			(net "Net_447")
		)
		(pad "AH1" smd oval
			(at -16.249396 0.103632 270)
			(size 0.254 0.3429)
			(layers "F.Cu" "F.Mask" "F.Paste")
			(net "PD_CPU_NODE1_RP1_PERN")
		)
		(pad "AH3" smd circle
			(at -15.304516 0.052832)
			(size 0.3048 0.3048)
			(layers "F.Cu" "F.Mask" "F.Paste")
			(net "PD_CPU_NODE1_RP1_PERP")
		)
		(pad "AH4" smd circle
			(at -14.542516 0.103632)
			(size 0.3048 0.3048)
			(layers "F.Cu" "F.Mask" "F.Paste")
			(net "PD_CPU_NODE1_RP1_PERN")
		)
		(pad "AH7" smd circle
			(at -13.344398 0.4699)
			(size 0.3048 0.3048)
			(layers "F.Cu" "F.Mask" "F.Paste")
			(net "GND")
		)
		(pad "AH8" smd circle
			(at -12.582398 0.4699)
			(size 0.3048 0.3048)
			(layers "F.Cu" "F.Mask" "F.Paste")
			(net "Net_398")
		)
		(pad "AH10" smd circle
			(at -11.820398 0.4699)
			(size 0.3048 0.3048)
			(layers "F.Cu" "F.Mask" "F.Paste")
			(net "Net_400")
		)
		(pad "AH11" smd circle
			(at -11.058398 0.4699)
			(size 0.3048 0.3048)
			(layers "F.Cu" "F.Mask" "F.Paste")
			(net "GND")
		)
		(pad "AH13" smd circle
			(at -10.296398 0.4699)
			(size 0.3048 0.3048)
			(layers "F.Cu" "F.Mask" "F.Paste")
			(net "Net_397")
		)
		(pad "AH14" smd circle
			(at -9.534398 0.4699)
			(size 0.3048 0.3048)
			(layers "F.Cu" "F.Mask" "F.Paste")
			(net "Net_372")
		)
		(pad "AH16" smd circle
			(at -8.772398 0.4699)
			(size 0.3048 0.3048)
			(layers "F.Cu" "F.Mask" "F.Paste")
			(net "GND")
		)
		(pad "AH17" smd circle
			(at -8.010398 0.4699)
			(size 0.3048 0.3048)
			(layers "F.Cu" "F.Mask" "F.Paste")
			(net "GND")
		)
		(pad "AH19" smd circle
			(at -7.248398 0.4699)
			(size 0.3048 0.3048)
			(layers "F.Cu" "F.Mask" "F.Paste")
			(net "GND")
		)
		(pad "AH48" smd circle
			(at 7.248398 0.230124)
			(size 0.3048 0.3048)
			(layers "F.Cu" "F.Mask" "F.Paste")
			(net "PD_CPU_NODE1_PUNIT_ST_ADDR1")
		)
		(pad "AH50" smd circle
			(at 8.010398 0.230124)
			(size 0.3048 0.3048)
			(layers "F.Cu" "F.Mask" "F.Paste")
			(net "TP_CPU0_NODE1_HFPLL")
		)
		(pad "AH51" smd circle
			(at 8.772398 0.230124)
			(size 0.3048 0.3048)
			(layers "F.Cu" "F.Mask" "F.Paste")
			(net "GND")
		)
		(pad "AH53" smd circle
			(at 9.534398 0.230124)
			(size 0.3048 0.3048)
			(layers "F.Cu" "F.Mask" "F.Paste")
			(net "FM_CPU_NODE1_OWDTOUT")
		)
		(pad "AH54" smd circle
			(at 10.296398 0.230124)
			(size 0.3048 0.3048)
			(layers "F.Cu" "F.Mask" "F.Paste")
			(net "Net_448")
		)
		(pad "AH56" smd circle
			(at 11.058398 0.230124)
			(size 0.3048 0.3048)
			(layers "F.Cu" "F.Mask" "F.Paste")
			(net "GND")
		)
		(pad "AH57" smd circle
			(at 11.820398 0.230124)
			(size 0.3048 0.3048)
			(layers "F.Cu" "F.Mask" "F.Paste")
			(net "Net_440")
		)
		(pad "AH59" smd circle
			(at 12.582398 0.230124)
			(size 0.3048 0.3048)
			(layers "F.Cu" "F.Mask" "F.Paste")
			(net "Net_441")
		)
		(pad "AH60" smd circle
			(at 13.344398 0.230124)
			(size 0.3048 0.3048)
			(layers "F.Cu" "F.Mask" "F.Paste")
			(net "GND")
		)
		(pad "AH62" smd circle
			(at 14.063218 0.407162)
			(size 0.3048 0.3048)
			(layers "F.Cu" "F.Mask" "F.Paste")
			(net "Net_443")
		)
		(pad "AJ2" smd circle
			(at -15.805658 0.863092)
			(size 0.3048 0.3048)
			(layers "F.Cu" "F.Mask" "F.Paste")
			(net "GND")
		)
		(pad "AJ4" smd circle
			(at -14.751558 0.783336)
			(size 0.3048 0.3048)
			(layers "F.Cu" "F.Mask" "F.Paste")
			(net "GND")
		)
		(pad "AJ5" smd circle
			(at -14.063218 0.614426)
			(size 0.3048 0.3048)
			(layers "F.Cu" "F.Mask" "F.Paste")
			(net "GND")
		)
		(pad "AJ21" smd circle
			(at -6.00075 0.8001)
			(size 0.381 0.381)
			(layers "F.Cu" "F.Mask" "F.Paste")
			(net "P1V5_NODE1_AJ21")
		)
		(pad "AJ23" smd circle
			(at -5.20065 0.8001)
			(size 0.381 0.381)
			(layers "F.Cu" "F.Mask" "F.Paste")
			(net "PD_CPU_NODE1_AJ23")
		)
		(pad "AJ25" smd circle
			(at -4.40055 0.8001)
			(size 0.381 0.381)
			(layers "F.Cu" "F.Mask" "F.Paste")
			(net "GND")
		)
		(pad "AJ26" smd circle
			(at -3.60045 0.8001)
			(size 0.381 0.381)
			(layers "F.Cu" "F.Mask" "F.Paste")
			(net "GND")
		)
		(pad "AJ28" smd circle
			(at -2.80035 0.8001)
			(size 0.381 0.381)
			(layers "F.Cu" "F.Mask" "F.Paste")
			(net "P1V5_NODE1")
		)
		(pad "AJ29" smd circle
			(at -2.00025 0.8001)
			(size 0.381 0.381)
			(layers "F.Cu" "F.Mask" "F.Paste")
			(net "GND")
		)
		(pad "AJ31" smd circle
			(at -1.20015 0.8001)
			(size 0.381 0.381)
			(layers "F.Cu" "F.Mask" "F.Paste")
			(net "P1V05_NODE1")
		)
		(pad "AJ32" smd circle
			(at -0.40005 0.8001)
			(size 0.381 0.381)
			(layers "F.Cu" "F.Mask" "F.Paste")
			(net "GND")
		)
		(pad "AJ34" smd circle
			(at 0.40005 0.8001)
			(size 0.381 0.381)
			(layers "F.Cu" "F.Mask" "F.Paste")
			(net "P1V05_NODE1")
		)
		(pad "AJ36" smd circle
			(at 1.20015 0.8001)
			(size 0.381 0.381)
			(layers "F.Cu" "F.Mask" "F.Paste")
			(net "GND")
		)
		(pad "AJ38" smd circle
			(at 2.00025 0.8001)
			(size 0.381 0.381)
			(layers "F.Cu" "F.Mask" "F.Paste")
			(net "P1V05_NODE1")
		)
		(pad "AJ39" smd circle
			(at 2.80035 0.8001)
			(size 0.381 0.381)
			(layers "F.Cu" "F.Mask" "F.Paste")
			(net "GND")
		)
		(pad "AJ41" smd circle
			(at 3.60045 0.8001)
			(size 0.381 0.381)
			(layers "F.Cu" "F.Mask" "F.Paste")
			(net "P1V05_NODE1")
		)
		(pad "AJ42" smd circle
			(at 4.40055 0.8001)
			(size 0.381 0.381)
			(layers "F.Cu" "F.Mask" "F.Paste")
			(net "GND")
		)
		(pad "AJ44" smd circle
			(at 5.20065 0.8001)
			(size 0.381 0.381)
			(layers "F.Cu" "F.Mask" "F.Paste")
			(net "P1V05_NODE1")
		)
		(pad "AJ46" smd circle
			(at 6.00075 0.8001)
			(size 0.381 0.381)
			(layers "F.Cu" "F.Mask" "F.Paste")
			(net "GND")
		)
		(pad "AJ47" smd circle
			(at 6.841998 0.816356)
			(size 0.3048 0.3048)
			(layers "F.Cu" "F.Mask" "F.Paste")
			(net "GND")
		)
		(pad "AJ63" smd circle
			(at 14.794738 0.564896)
			(size 0.3048 0.3048)
			(layers "F.Cu" "F.Mask" "F.Paste")
			(net "Net_436")
		)
	)
)
